# T6G (Grand Teton) — schematic netlist excerpt (pin names and nets, part order shuffled) for the footprints in the layout excerpt that follows; sources: Cadence DE-HDL packaged netlist, KiCad conversion of 04192023_DAF0TMB3IC0_F0TG_MB_C_brd_V02_OCP.brd

PC135_5  Q_CAP  1UF 25V 10% X6S  pkg C0402  page 203 : A = SW_P12V_AUX_PVDDCR_CPU1_P0_FLT ; B = GND
R6230  Q_RES  2.2K 5% CHIP  pkg 0402LF  page 267 : A = P3V3_AUX ; B = SMB_P12V_HSC_SDA

(kicad_pcb
	(version 20260206)
	(generator "pcbnew")
	(generator_version "10.0")
	(general
		(thickness 1.6)
		(legacy_teardrops no)
	)
	(paper "A4")
	(title_block
		(title "04192023_DAF0TMB3IC0_F0TG_MB_C_brd_V02_OCP.brd")
		(comment 1 "Grand Teton / footprints 1887-1888 of 8354")
	)
	(layers
		(0 "F.Cu" signal "TOP")
		(4 "In1.Cu" signal "GND")
		(6 "In2.Cu" signal "IN1")
		(8 "In3.Cu" signal "GND1")
		(10 "In4.Cu" signal "IN2")
		(12 "In5.Cu" signal "GND2")
		(14 "In6.Cu" signal "IN3")
		(16 "In7.Cu" signal "GND3")
		(18 "In8.Cu" signal "VCC")
		(20 "In9.Cu" signal "VCC1")
		(22 "In10.Cu" signal "GND4")
		(24 "In11.Cu" signal "IN4")
		(26 "In12.Cu" signal "GND5")
		(28 "In13.Cu" signal "IN5")
		(30 "In14.Cu" signal "GND6")
		(32 "In15.Cu" signal "IN6")
		(34 "In16.Cu" signal "GND7")
		(2 "B.Cu" signal "BOTTOM")
		(9 "F.Adhes" user "F.Adhesive")
		(11 "B.Adhes" user "B.Adhesive")
		(13 "F.Paste" user "Package Geometry/Pastemask Top")
		(15 "B.Paste" user "Package Geometry/Pastemask Bottom")
		(5 "F.SilkS" user "Ref Des/Silkscreen Top")
		(7 "B.SilkS" user "Ref Des/Silkscreen Bottom")
		(1 "F.Mask" user "Board Geometry/Soldermask Top")
		(3 "B.Mask" user "Board Geometry/Soldermask Bottom")
		(17 "Dwgs.User" user "User.Drawings")
		(19 "Cmts.User" user "User.Comments")
		(21 "Eco1.User" user "User.Eco1")
		(23 "Eco2.User" user "User.Eco2")
		(25 "Edge.Cuts" user "Board Geometry/Outline")
		(27 "Margin" user)
		(31 "F.CrtYd" user "Package Geometry/Place Bound Top")
		(29 "B.CrtYd" user "Package Geometry/Place Bound Bottom")
		(35 "F.Fab" user "Ref Des/Assembly Top")
		(33 "B.Fab" user "Ref Des/Assembly Bottom")
	)
	(footprint ""
		(layer "F.Cu")
		(at 347.024706 -335.17459 -90)
		(property "Reference" "PC135_5"
			(at 0 0 270)
			(layer "F.SilkS")
			(hide yes)
			(effects
				(font
					(size 1.27 1.27)
				)
			)
		)
		(property "Value" ""
			(at 0 0 270)
			(layer "F.Fab")
			(effects
				(font
					(size 1.27 1.27)
				)
			)
		)
		(duplicate_pad_numbers_are_jumpers no)
		(fp_line
			(start -0.7874 0.4064)
			(end -0.7874 -0.4064)
			(stroke
				(width 0.1524)
				(type default)
			)
			(layer "F.SilkS")
		)
		(fp_line
			(start 0.7874 0.4064)
			(end -0.7874 0.4064)
			(stroke
				(width 0.1524)
				(type default)
			)
			(layer "F.SilkS")
		)
		(fp_line
			(start -0.7874 -0.4064)
			(end 0.7874 -0.4064)
			(stroke
				(width 0.1524)
				(type default)
			)
			(layer "F.SilkS")
		)
		(fp_line
			(start 0.7874 -0.4064)
			(end 0.7874 0.4064)
			(stroke
				(width 0.1524)
				(type default)
			)
			(layer "F.SilkS")
		)
		(fp_line
			(start -0.67945 0.3048)
			(end -0.67945 -0.305054)
			(stroke
				(width 0.1)
				(type default)
			)
			(layer "F.Fab")
		)
		(fp_line
			(start -0.12065 0.3048)
			(end -0.67945 0.3048)
			(stroke
				(width 0.1)
				(type default)
			)
			(layer "F.Fab")
		)
		(fp_line
			(start 0.120396 0.3048)
			(end 0.120396 0.2794)
			(stroke
				(width 0.1)
				(type default)
			)
			(layer "F.Fab")
		)
		(fp_line
			(start 0.67945 0.3048)
			(end 0.120396 0.3048)
			(stroke
				(width 0.1)
				(type default)
			)
			(layer "F.Fab")
		)
		(fp_line
			(start -0.12065 0.2794)
			(end -0.12065 0.3048)
			(stroke
				(width 0.1)
				(type default)
			)
			(layer "F.Fab")
		)
		(fp_line
			(start 0.120396 0.2794)
			(end -0.12065 0.2794)
			(stroke
				(width 0.1)
				(type default)
			)
			(layer "F.Fab")
		)
		(fp_line
			(start -0.12065 -0.2794)
			(end 0.12065 -0.2794)
			(stroke
				(width 0.1)
				(type default)
			)
			(layer "F.Fab")
		)
		(fp_line
			(start 0.12065 -0.2794)
			(end 0.12065 -0.3048)
			(stroke
				(width 0.1)
				(type default)
			)
			(layer "F.Fab")
		)
		(fp_line
			(start 0.12065 -0.3048)
			(end 0.67945 -0.3048)
			(stroke
				(width 0.1)
				(type default)
			)
			(layer "F.Fab")
		)
		(fp_line
			(start 0.67945 -0.3048)
			(end 0.67945 0.3048)
			(stroke
				(width 0.1)
				(type default)
			)
			(layer "F.Fab")
		)
		(fp_line
			(start -0.67945 -0.305054)
			(end -0.12065 -0.305054)
			(stroke
				(width 0.1)
				(type default)
			)
			(layer "F.Fab")
		)
		(fp_line
			(start -0.12065 -0.305054)
			(end -0.12065 -0.2794)
			(stroke
				(width 0.1)
				(type default)
			)
			(layer "F.Fab")
		)
		(pad "1" smd circle
			(at -0.40005 0 270)
			(size 0 0)
			(layers "F.Cu" "F.Mask" "F.Paste")
			(net "SW_P12V_AUX_PVDDCR_CPU1_P0_FLT")
		)
		(pad "2" smd circle
			(at 0.40005 0 270)
			(size 0 0)
			(layers "F.Cu" "F.Mask" "F.Paste")
			(net "GND")
		)
	)
	(footprint ""
		(layer "F.Cu")
		(at 281.621738 -388.71652 90)
		(property "Reference" "R6230"
			(at 0 0 90)
			(layer "F.SilkS")
			(hide yes)
			(effects
				(font
					(size 1.27 1.27)
				)
			)
		)
		(property "Value" ""
			(at 0 0 90)
			(layer "F.Fab")
			(effects
				(font
					(size 1.27 1.27)
				)
			)
		)
		(duplicate_pad_numbers_are_jumpers no)
		(fp_line
			(start 0.7874 -0.4064)
			(end 0.7874 0.4064)
			(stroke
				(width 0.1524)
				(type default)
			)
			(layer "F.SilkS")
		)
		(fp_line
			(start -0.7874 -0.4064)
			(end 0.7874 -0.4064)
			(stroke
				(width 0.1524)
				(type default)
			)
			(layer "F.SilkS")
		)
		(fp_line
			(start 0.7874 0.4064)
			(end -0.7874 0.4064)
			(stroke
				(width 0.1524)
				(type default)
			)
			(layer "F.SilkS")
		)
		(fp_line
			(start -0.7874 0.4064)
			(end -0.7874 -0.4064)
			(stroke
				(width 0.1524)
				(type default)
			)
			(layer "F.SilkS")
		)
		(fp_line
			(start -0.12065 -0.305054)
			(end -0.12065 -0.2794)
			(stroke
				(width 0.1)
				(type default)
			)
			(layer "F.Fab")
		)
		(fp_line
			(start -0.67945 -0.305054)
			(end -0.12065 -0.305054)
			(stroke
				(width 0.1)
				(type default)
			)
			(layer "F.Fab")
		)
		(fp_line
			(start 0.67945 -0.3048)
			(end 0.67945 0.3048)
			(stroke
				(width 0.1)
				(type default)
			)
			(layer "F.Fab")
		)
		(fp_line
			(start 0.12065 -0.3048)
			(end 0.67945 -0.3048)
			(stroke
				(width 0.1)
				(type default)
			)
			(layer "F.Fab")
		)
		(fp_line
			(start 0.12065 -0.2794)
			(end 0.12065 -0.3048)
			(stroke
				(width 0.1)
				(type default)
			)
			(layer "F.Fab")
		)
		(fp_line
			(start -0.12065 -0.2794)
			(end 0.12065 -0.2794)
			(stroke
				(width 0.1)
				(type default)
			)
			(layer "F.Fab")
		)
		(fp_line
			(start 0.120396 0.2794)
			(end -0.12065 0.2794)
			(stroke
				(width 0.1)
				(type default)
			)
			(layer "F.Fab")
		)
		(fp_line
			(start -0.12065 0.2794)
			(end -0.12065 0.3048)
			(stroke
				(width 0.1)
				(type default)
			)
			(layer "F.Fab")
		)
		(fp_line
			(start 0.67945 0.3048)
			(end 0.120396 0.3048)
			(stroke
				(width 0.1)
				(type default)
			)
			(layer "F.Fab")
		)
		(fp_line
			(start 0.120396 0.3048)
			(end 0.120396 0.2794)
			(stroke
				(width 0.1)
				(type default)
			)
			(layer "F.Fab")
		)
		(fp_line
			(start -0.12065 0.3048)
			(end -0.67945 0.3048)
			(stroke
				(width 0.1)
				(type default)
			)
			(layer "F.Fab")
		)
		(fp_line
			(start -0.67945 0.3048)
			(end -0.67945 -0.305054)
			(stroke
				(width 0.1)
				(type default)
			)
			(layer "F.Fab")
		)
		(pad "1" smd circle
			(at -0.40005 0 90)
			(size 0 0)
			(layers "F.Cu" "F.Mask" "F.Paste")
			(net "P3V3_AUX")
		)
		(pad "2" smd circle
			(at 0.40005 0 90)
			(size 0 0)
			(layers "F.Cu" "F.Mask" "F.Paste")
			(net "SMB_P12V_HSC_SDA")
		)
	)
)
